(kicad_pcb
	(version 20260206)
	(generator "pcbnew")
	(generator_version "10.0")
	(general
		(thickness 1.6)
		(legacy_teardrops no)
	)
	(paper "A4")
	(title_block
		(title "04192023_DAF0TMB3IC0_F0TG_MB_C_brd_V02_OCP.brd")
		(comment 1 "Grand Teton / footprints 762-767 of 8354")
	)
	(layers
		(0 "F.Cu" signal "TOP")
		(4 "In1.Cu" signal "GND")
		(6 "In2.Cu" signal "IN1")
		(8 "In3.Cu" signal "GND1")
		(10 "In4.Cu" signal "IN2")
		(12 "In5.Cu" signal "GND2")
		(14 "In6.Cu" signal "IN3")
		(16 "In7.Cu" signal "GND3")
		(18 "In8.Cu" signal "VCC")
		(20 "In9.Cu" signal "VCC1")
		(22 "In10.Cu" signal "GND4")
		(24 "In11.Cu" signal "IN4")
		(26 "In12.Cu" signal "GND5")
		(28 "In13.Cu" signal "IN5")
		(30 "In14.Cu" signal "GND6")
		(32 "In15.Cu" signal "IN6")
		(34 "In16.Cu" signal "GND7")
		(2 "B.Cu" signal "BOTTOM")
		(9 "F.Adhes" user "F.Adhesive")
		(11 "B.Adhes" user "B.Adhesive")
		(13 "F.Paste" user "Package Geometry/Pastemask Top")
		(15 "B.Paste" user "Package Geometry/Pastemask Bottom")
		(5 "F.SilkS" user "Ref Des/Silkscreen Top")
		(7 "B.SilkS" user "Ref Des/Silkscreen Bottom")
		(1 "F.Mask" user "Board Geometry/Soldermask Top")
		(3 "B.Mask" user "Board Geometry/Soldermask Bottom")
		(17 "Dwgs.User" user "User.Drawings")
		(19 "Cmts.User" user "User.Comments")
		(21 "Eco1.User" user "User.Eco1")
		(23 "Eco2.User" user "User.Eco2")
		(25 "Edge.Cuts" user "Board Geometry/Outline")
		(27 "Margin" user)
		(31 "F.CrtYd" user "Package Geometry/Place Bound Top")
		(29 "B.CrtYd" user "Package Geometry/Place Bound Bottom")
		(35 "F.Fab" user "Ref Des/Assembly Top")
		(33 "B.Fab" user "Ref Des/Assembly Bottom")
	)
	(footprint ""
		(layer "F.Cu")
		(at 44.2087 -116.10086 90)
		(property "Reference" "Q7003"
			(at -2.4384 -3.292348 90)
			(unlocked yes)
			(layer "F.SilkS")
			(effects
				(font
					(size 0.7874 0.5842)
					(thickness 0.1524)
				)
				(justify left)
			)
		)
		(property "Value" ""
			(at 0 0 90)
			(layer "F.Fab")
			(effects
				(font
					(size 1.27 1.27)
				)
			)
		)
		(duplicate_pad_numbers_are_jumpers no)
		(fp_line
			(start 2.350008 -2.649982)
			(end 2.350008 -2.4892)
			(stroke
				(width 0.1524)
				(type default)
			)
			(layer "F.SilkS")
		)
		(fp_line
			(start -2.350008 -2.649982)
			(end 2.350008 -2.649982)
			(stroke
				(width 0.1524)
				(type default)
			)
			(layer "F.SilkS")
		)
		(fp_line
			(start -2.350008 -2.4384)
			(end -2.350008 -2.649982)
			(stroke
				(width 0.1524)
				(type default)
			)
			(layer "F.SilkS")
		)
		(fp_line
			(start 2.350008 2.4892)
			(end 2.350008 2.649982)
			(stroke
				(width 0.1524)
				(type default)
			)
			(layer "F.SilkS")
		)
		(fp_line
			(start 2.350008 2.649982)
			(end -2.350008 2.649982)
			(stroke
				(width 0.1524)
				(type default)
			)
			(layer "F.SilkS")
		)
		(fp_line
			(start -2.350008 2.649982)
			(end -2.350008 2.413)
			(stroke
				(width 0.1524)
				(type default)
			)
			(layer "F.SilkS")
		)
		(fp_poly
			(pts
				(xy -3.717544 -1.905) (xy -4.758944 -2.3241) (xy -4.758944 -1.524)
			)
			(stroke
				(width 0)
				(type default)
			)
			(fill yes)
			(layer "F.SilkS")
		)
		(fp_line
			(start 2.350008 -2.649982)
			(end 2.350008 2.649982)
			(stroke
				(width 0.1)
				(type default)
			)
			(layer "F.Fab")
		)
		(fp_line
			(start -2.350008 -2.649982)
			(end 2.350008 -2.649982)
			(stroke
				(width 0.1)
				(type default)
			)
			(layer "F.Fab")
		)
		(fp_line
			(start 2.350008 2.649982)
			(end -2.350008 2.649982)
			(stroke
				(width 0.1)
				(type default)
			)
			(layer "F.Fab")
		)
		(fp_line
			(start -2.350008 2.649982)
			(end -2.350008 -2.649982)
			(stroke
				(width 0.1)
				(type default)
			)
			(layer "F.Fab")
		)
		(fp_poly
			(pts
				(xy -3.717544 -1.905) (xy -4.758944 -2.3241) (xy -4.758944 -1.524)
			)
			(stroke
				(width 0)
				(type default)
			)
			(fill yes)
			(layer "F.Fab")
		)
		(pad "1" smd rect
			(at -2.999994 -1.905)
			(size 0.7112 1.1684)
			(layers "F.Cu" "F.Mask" "F.Paste")
			(net "GND")
		)
		(pad "2" smd rect
			(at -2.999994 -0.635)
			(size 0.7112 1.1684)
			(layers "F.Cu" "F.Mask" "F.Paste")
			(net "GND")
		)
		(pad "3" smd rect
			(at -2.999994 0.635)
			(size 0.7112 1.1684)
			(layers "F.Cu" "F.Mask" "F.Paste")
			(net "GND")
		)
		(pad "4" smd rect
			(at -2.999994 1.905)
			(size 0.7112 1.1684)
			(layers "F.Cu" "F.Mask" "F.Paste")
			(net "P3V3_AUX_DSC_G2")
		)
		(pad "5" smd circle
			(at 0.925068 0)
			(size 0 0)
			(layers "F.Cu" "F.Mask" "F.Paste")
			(net "P3V3_AUX_DSC")
		)
		(zone
			(layer "F.Cu")
			(hatch none 0.5)
			(connect_pads
				(clearance 0)
			)
			(min_thickness 0.25)
			(keepout
				(tracks not_allowed)
				(vias allowed)
				(pads allowed)
				(copperpour not_allowed)
				(footprints allowed)
			)
			(placement
				(enabled no)
				(sheetname "")
			)
			(fill
				(thermal_gap 0.5)
				(thermal_bridge_width 0.5)
				(island_removal_mode 0)
			)
			(polygon
				(pts
					(xy 41.5671 -118.43766) (xy 41.7957 -118.43766) (xy 41.7957 -117.75186) (xy 42.0497 -117.75186)
					(xy 42.0497 -114.65306) (xy 46.3677 -114.65306) (xy 46.3677 -117.75186) (xy 46.6217 -117.75186)
					(xy 46.6217 -118.43766) (xy 46.8503 -118.43766) (xy 46.8503 -113.75136) (xy 41.5671 -113.75136)
				)
			)
		)
	)
	(footprint ""
		(layer "F.Cu")
		(at 257.85953 -56.495442)
		(property "Reference" "R3956"
			(at 0 0 0)
			(layer "F.SilkS")
			(hide yes)
			(effects
				(font
					(size 1.27 1.27)
				)
			)
		)
		(property "Value" ""
			(at 0 0 0)
			(layer "F.Fab")
			(effects
				(font
					(size 1.27 1.27)
				)
			)
		)
		(duplicate_pad_numbers_are_jumpers no)
		(fp_line
			(start -0.7874 -0.4064)
			(end 0.7874 -0.4064)
			(stroke
				(width 0.1524)
				(type default)
			)
			(layer "F.SilkS")
		)
		(fp_line
			(start -0.7874 0.4064)
			(end -0.7874 -0.4064)
			(stroke
				(width 0.1524)
				(type default)
			)
			(layer "F.SilkS")
		)
		(fp_line
			(start 0.7874 -0.4064)
			(end 0.7874 0.4064)
			(stroke
				(width 0.1524)
				(type default)
			)
			(layer "F.SilkS")
		)
		(fp_line
			(start 0.7874 0.4064)
			(end -0.7874 0.4064)
			(stroke
				(width 0.1524)
				(type default)
			)
			(layer "F.SilkS")
		)
		(fp_line
			(start -0.67945 -0.305054)
			(end -0.12065 -0.305054)
			(stroke
				(width 0.1)
				(type default)
			)
			(layer "F.Fab")
		)
		(fp_line
			(start -0.67945 0.3048)
			(end -0.67945 -0.305054)
			(stroke
				(width 0.1)
				(type default)
			)
			(layer "F.Fab")
		)
		(fp_line
			(start -0.12065 -0.305054)
			(end -0.12065 -0.2794)
			(stroke
				(width 0.1)
				(type default)
			)
			(layer "F.Fab")
		)
		(fp_line
			(start -0.12065 -0.2794)
			(end 0.12065 -0.2794)
			(stroke
				(width 0.1)
				(type default)
			)
			(layer "F.Fab")
		)
		(fp_line
			(start -0.12065 0.2794)
			(end -0.12065 0.3048)
			(stroke
				(width 0.1)
				(type default)
			)
			(layer "F.Fab")
		)
		(fp_line
			(start -0.12065 0.3048)
			(end -0.67945 0.3048)
			(stroke
				(width 0.1)
				(type default)
			)
			(layer "F.Fab")
		)
		(fp_line
			(start 0.120396 0.2794)
			(end -0.12065 0.2794)
			(stroke
				(width 0.1)
				(type default)
			)
			(layer "F.Fab")
		)
		(fp_line
			(start 0.120396 0.3048)
			(end 0.120396 0.2794)
			(stroke
				(width 0.1)
				(type default)
			)
			(layer "F.Fab")
		)
		(fp_line
			(start 0.12065 -0.3048)
			(end 0.67945 -0.3048)
			(stroke
				(width 0.1)
				(type default)
			)
			(layer "F.Fab")
		)
		(fp_line
			(start 0.12065 -0.2794)
			(end 0.12065 -0.3048)
			(stroke
				(width 0.1)
				(type default)
			)
			(layer "F.Fab")
		)
		(fp_line
			(start 0.67945 -0.3048)
			(end 0.67945 0.3048)
			(stroke
				(width 0.1)
				(type default)
			)
			(layer "F.Fab")
		)
		(fp_line
			(start 0.67945 0.3048)
			(end 0.120396 0.3048)
			(stroke
				(width 0.1)
				(type default)
			)
			(layer "F.Fab")
		)
		(pad "1" smd circle
			(at -0.40005 0)
			(size 0 0)
			(layers "F.Cu" "F.Mask" "F.Paste")
			(net "P12V_E1S_IMON_0")
		)
		(pad "2" smd circle
			(at 0.40005 0)
			(size 0 0)
			(layers "F.Cu" "F.Mask" "F.Paste")
			(net "P12V_E1S_0_ISENSE_MPS_TIC")
		)
	)
	(footprint ""
		(layer "F.Cu")
		(at 130.184906 -408.517344 -90)
		(property "Reference" "C6704"
			(at 0 0 270)
			(layer "F.SilkS")
			(hide yes)
			(effects
				(font
					(size 1.27 1.27)
				)
			)
		)
		(property "Value" ""
			(at 0 0 270)
			(layer "F.Fab")
			(effects
				(font
					(size 1.27 1.27)
				)
			)
		)
		(duplicate_pad_numbers_are_jumpers no)
		(fp_line
			(start -0.299974 0.150114)
			(end -0.299974 -0.150114)
			(stroke
				(width 0.1)
				(type default)
			)
			(layer "F.Fab")
		)
		(fp_line
			(start 0.299974 0.150114)
			(end -0.299974 0.150114)
			(stroke
				(width 0.1)
				(type default)
			)
			(layer "F.Fab")
		)
		(fp_line
			(start -0.299974 -0.150114)
			(end 0.299974 -0.150114)
			(stroke
				(width 0.1)
				(type default)
			)
			(layer "F.Fab")
		)
		(fp_line
			(start 0.299974 -0.150114)
			(end 0.299974 0.150114)
			(stroke
				(width 0.1)
				(type default)
			)
			(layer "F.Fab")
		)
		(pad "1" smd rect
			(at -0.2667 0 270)
			(size 0.3048 0.381)
			(layers "F.Cu" "F.Mask" "F.Paste")
			(net "P5E_CPU1_P2_TX_BUF_C_DN<5>")
		)
		(pad "2" smd rect
			(at 0.2667 0 270)
			(size 0.3048 0.381)
			(layers "F.Cu" "F.Mask" "F.Paste")
			(net "P5E_CPU1_P2_TX_BUF_DN<5>")
		)
	)
	(footprint ""
		(layer "F.Cu")
		(at 273.35734 -116.321586)
		(property "Reference" "R6228"
			(at 0 0 0)
			(layer "F.SilkS")
			(hide yes)
			(effects
				(font
					(size 1.27 1.27)
				)
			)
		)
		(property "Value" ""
			(at 0 0 0)
			(layer "F.Fab")
			(effects
				(font
					(size 1.27 1.27)
				)
			)
		)
		(duplicate_pad_numbers_are_jumpers no)
		(fp_line
			(start -0.7874 -0.4064)
			(end 0.7874 -0.4064)
			(stroke
				(width 0.1524)
				(type default)
			)
			(layer "F.SilkS")
		)
		(fp_line
			(start -0.7874 0.4064)
			(end -0.7874 -0.4064)
			(stroke
				(width 0.1524)
				(type default)
			)
			(layer "F.SilkS")
		)
		(fp_line
			(start 0.7874 -0.4064)
			(end 0.7874 0.4064)
			(stroke
				(width 0.1524)
				(type default)
			)
			(layer "F.SilkS")
		)
		(fp_line
			(start 0.7874 0.4064)
			(end -0.7874 0.4064)
			(stroke
				(width 0.1524)
				(type default)
			)
			(layer "F.SilkS")
		)
		(fp_line
			(start -0.67945 -0.305054)
			(end -0.12065 -0.305054)
			(stroke
				(width 0.1)
				(type default)
			)
			(layer "F.Fab")
		)
		(fp_line
			(start -0.67945 0.3048)
			(end -0.67945 -0.305054)
			(stroke
				(width 0.1)
				(type default)
			)
			(layer "F.Fab")
		)
		(fp_line
			(start -0.12065 -0.305054)
			(end -0.12065 -0.2794)
			(stroke
				(width 0.1)
				(type default)
			)
			(layer "F.Fab")
		)
		(fp_line
			(start -0.12065 -0.2794)
			(end 0.12065 -0.2794)
			(stroke
				(width 0.1)
				(type default)
			)
			(layer "F.Fab")
		)
		(fp_line
			(start -0.12065 0.2794)
			(end -0.12065 0.3048)
			(stroke
				(width 0.1)
				(type default)
			)
			(layer "F.Fab")
		)
		(fp_line
			(start -0.12065 0.3048)
			(end -0.67945 0.3048)
			(stroke
				(width 0.1)
				(type default)
			)
			(layer "F.Fab")
		)
		(fp_line
			(start 0.120396 0.2794)
			(end -0.12065 0.2794)
			(stroke
				(width 0.1)
				(type default)
			)
			(layer "F.Fab")
		)
		(fp_line
			(start 0.120396 0.3048)
			(end 0.120396 0.2794)
			(stroke
				(width 0.1)
				(type default)
			)
			(layer "F.Fab")
		)
		(fp_line
			(start 0.12065 -0.3048)
			(end 0.67945 -0.3048)
			(stroke
				(width 0.1)
				(type default)
			)
			(layer "F.Fab")
		)
		(fp_line
			(start 0.12065 -0.2794)
			(end 0.12065 -0.3048)
			(stroke
				(width 0.1)
				(type default)
			)
			(layer "F.Fab")
		)
		(fp_line
			(start 0.67945 -0.3048)
			(end 0.67945 0.3048)
			(stroke
				(width 0.1)
				(type default)
			)
			(layer "F.Fab")
		)
		(fp_line
			(start 0.67945 0.3048)
			(end 0.120396 0.3048)
			(stroke
				(width 0.1)
				(type default)
			)
			(layer "F.Fab")
		)
		(pad "1" smd circle
			(at -0.40005 0)
			(size 0 0)
			(layers "F.Cu" "F.Mask" "F.Paste")
			(net "SMB_P12V_HSC_SDA_R")
		)
		(pad "2" smd circle
			(at 0.40005 0)
			(size 0 0)
			(layers "F.Cu" "F.Mask" "F.Paste")
			(net "SMB_P12V_HSC_SDA")
		)
	)
	(footprint ""
		(layer "F.Cu")
		(at 62.623954 -375.49963 -90)
		(property "Reference" "C816"
			(at 0 0 270)
			(layer "F.SilkS")
			(hide yes)
			(effects
				(font
					(size 1.27 1.27)
				)
			)
		)
		(property "Value" ""
			(at 0 0 270)
			(layer "F.Fab")
			(effects
				(font
					(size 1.27 1.27)
				)
			)
		)
		(duplicate_pad_numbers_are_jumpers no)
		(fp_line
			(start -0.299974 0.150114)
			(end -0.299974 -0.150114)
			(stroke
				(width 0.1)
				(type default)
			)
			(layer "F.Fab")
		)
		(fp_line
			(start 0.299974 0.150114)
			(end -0.299974 0.150114)
			(stroke
				(width 0.1)
				(type default)
			)
			(layer "F.Fab")
		)
		(fp_line
			(start -0.299974 -0.150114)
			(end 0.299974 -0.150114)
			(stroke
				(width 0.1)
				(type default)
			)
			(layer "F.Fab")
		)
		(fp_line
			(start 0.299974 -0.150114)
			(end 0.299974 0.150114)
			(stroke
				(width 0.1)
				(type default)
			)
			(layer "F.Fab")
		)
		(pad "1" smd rect
			(at -0.2667 0 270)
			(size 0.3048 0.381)
			(layers "F.Cu" "F.Mask" "F.Paste")
			(net "P5E_CPU1_P0_TX_C_DN<10>")
		)
		(pad "2" smd rect
			(at 0.2667 0 270)
			(size 0.3048 0.381)
			(layers "F.Cu" "F.Mask" "F.Paste")
			(net "P5E_CPU1_P0_TX_DN<10>")
		)
	)
	(footprint ""
		(layer "F.Cu")
		(at 234.301538 -293.13505 -90)
		(property "Reference" "PC6525"
			(at 0 0 270)
			(layer "F.SilkS")
			(hide yes)
			(effects
				(font
					(size 1.27 1.27)
				)
			)
		)
		(property "Value" ""
			(at 0 0 270)
			(layer "F.Fab")
			(effects
				(font
					(size 1.27 1.27)
				)
			)
		)
		(duplicate_pad_numbers_are_jumpers no)
		(fp_line
			(start -0.7874 0.4064)
			(end -0.7874 -0.4064)
			(stroke
				(width 0.1524)
				(type default)
			)
			(layer "F.SilkS")
		)
		(fp_line
			(start 0.7874 0.4064)
			(end -0.7874 0.4064)
			(stroke
				(width 0.1524)
				(type default)
			)
			(layer "F.SilkS")
		)
		(fp_line
			(start -0.7874 -0.4064)
			(end 0.7874 -0.4064)
			(stroke
				(width 0.1524)
				(type default)
			)
			(layer "F.SilkS")
		)
		(fp_line
			(start 0.7874 -0.4064)
			(end 0.7874 0.4064)
			(stroke
				(width 0.1524)
				(type default)
			)
			(layer "F.SilkS")
		)
		(fp_line
			(start -0.67945 0.3048)
			(end -0.67945 -0.305054)
			(stroke
				(width 0.1)
				(type default)
			)
			(layer "F.Fab")
		)
		(fp_line
			(start -0.12065 0.3048)
			(end -0.67945 0.3048)
			(stroke
				(width 0.1)
				(type default)
			)
			(layer "F.Fab")
		)
		(fp_line
			(start 0.120396 0.3048)
			(end 0.120396 0.2794)
			(stroke
				(width 0.1)
				(type default)
			)
			(layer "F.Fab")
		)
		(fp_line
			(start 0.67945 0.3048)
			(end 0.120396 0.3048)
			(stroke
				(width 0.1)
				(type default)
			)
			(layer "F.Fab")
		)
		(fp_line
			(start -0.12065 0.2794)
			(end -0.12065 0.3048)
			(stroke
				(width 0.1)
				(type default)
			)
			(layer "F.Fab")
		)
		(fp_line
			(start 0.120396 0.2794)
			(end -0.12065 0.2794)
			(stroke
				(width 0.1)
				(type default)
			)
			(layer "F.Fab")
		)
		(fp_line
			(start -0.12065 -0.2794)
			(end 0.12065 -0.2794)
			(stroke
				(width 0.1)
				(type default)
			)
			(layer "F.Fab")
		)
		(fp_line
			(start 0.12065 -0.2794)
			(end 0.12065 -0.3048)
			(stroke
				(width 0.1)
				(type default)
			)
			(layer "F.Fab")
		)
		(fp_line
			(start 0.12065 -0.3048)
			(end 0.67945 -0.3048)
			(stroke
				(width 0.1)
				(type default)
			)
			(layer "F.Fab")
		)
		(fp_line
			(start 0.67945 -0.3048)
			(end 0.67945 0.3048)
			(stroke
				(width 0.1)
				(type default)
			)
			(layer "F.Fab")
		)
		(fp_line
			(start -0.67945 -0.305054)
			(end -0.12065 -0.305054)
			(stroke
				(width 0.1)
				(type default)
			)
			(layer "F.Fab")
		)
		(fp_line
			(start -0.12065 -0.305054)
			(end -0.12065 -0.2794)
			(stroke
				(width 0.1)
				(type default)
			)
			(layer "F.Fab")
		)
		(pad "1" smd circle
			(at -0.40005 0 270)
			(size 0 0)
			(layers "F.Cu" "F.Mask" "F.Paste")
			(net "P1V8_RETIMER_CPU1_VCC")
		)
		(pad "2" smd circle
			(at 0.40005 0 270)
			(size 0 0)
			(layers "F.Cu" "F.Mask" "F.Paste")
			(net "GND")
		)
	)
)
